# T6G (Grand Teton) — schematic netlist excerpt (pin names and nets, part order shuffled) for the footprints in the layout excerpt that follows; sources: Cadence DE-HDL packaged netlist, KiCad conversion of 04192023_DAF0TMB3IC0_F0TG_MB_C_brd_V02_OCP.brd

PC598  Q_CAPP  470UF 2.5V 20% SPCAP  pkg SMLF  page 198 : A = PVDDCR_SOC_P0 ; B = GND
R5  Q_RES  54.9K 1% CHIP  pkg 0402LF  page 90 : A = PD_CHE_CPU0_DIMM_SAA ; B = GND
C600  Q_CAP  0.1UF 10V 10% X7S  pkg C0201  page 290 : A = P1V8_CPU0_RT1_1A ; B = GND

(kicad_pcb
	(version 20260206)
	(generator "pcbnew")
	(generator_version "10.0")
	(general
		(thickness 1.6)
		(legacy_teardrops no)
	)
	(paper "A4")
	(title_block
		(title "04192023_DAF0TMB3IC0_F0TG_MB_C_brd_V02_OCP.brd")
		(comment 1 "Grand Teton / footprints 7191-7193 of 8354")
	)
	(layers
		(0 "F.Cu" signal "TOP")
		(4 "In1.Cu" signal "GND")
		(6 "In2.Cu" signal "IN1")
		(8 "In3.Cu" signal "GND1")
		(10 "In4.Cu" signal "IN2")
		(12 "In5.Cu" signal "GND2")
		(14 "In6.Cu" signal "IN3")
		(16 "In7.Cu" signal "GND3")
		(18 "In8.Cu" signal "VCC")
		(20 "In9.Cu" signal "VCC1")
		(22 "In10.Cu" signal "GND4")
		(24 "In11.Cu" signal "IN4")
		(26 "In12.Cu" signal "GND5")
		(28 "In13.Cu" signal "IN5")
		(30 "In14.Cu" signal "GND6")
		(32 "In15.Cu" signal "IN6")
		(34 "In16.Cu" signal "GND7")
		(2 "B.Cu" signal "BOTTOM")
		(9 "F.Adhes" user "F.Adhesive")
		(11 "B.Adhes" user "B.Adhesive")
		(13 "F.Paste" user "Package Geometry/Pastemask Top")
		(15 "B.Paste" user "Package Geometry/Pastemask Bottom")
		(5 "F.SilkS" user "Ref Des/Silkscreen Top")
		(7 "B.SilkS" user "Ref Des/Silkscreen Bottom")
		(1 "F.Mask" user "Board Geometry/Soldermask Top")
		(3 "B.Mask" user "Board Geometry/Soldermask Bottom")
		(17 "Dwgs.User" user "User.Drawings")
		(19 "Cmts.User" user "User.Comments")
		(21 "Eco1.User" user "User.Eco1")
		(23 "Eco2.User" user "User.Eco2")
		(25 "Edge.Cuts" user "Board Geometry/Outline")
		(27 "Margin" user)
		(31 "F.CrtYd" user "Package Geometry/Place Bound Top")
		(29 "B.CrtYd" user "Package Geometry/Place Bound Bottom")
		(35 "F.Fab" user "Ref Des/Assembly Top")
		(33 "B.Fab" user "Ref Des/Assembly Bottom")
	)
	(footprint ""
		(layer "B.Cu")
		(at 273.847814 -194.88531 180)
		(property "Reference" "R5"
			(at 0 0 0)
			(layer "B.SilkS")
			(hide yes)
			(effects
				(font
					(size 1.27 1.27)
				)
				(justify mirror)
			)
		)
		(property "Value" ""
			(at 0 0 0)
			(layer "B.Fab")
			(effects
				(font
					(size 1.27 1.27)
				)
				(justify mirror)
			)
		)
		(duplicate_pad_numbers_are_jumpers no)
		(fp_line
			(start 0.7874 0.4064)
			(end 0.7874 -0.4064)
			(stroke
				(width 0.1524)
				(type default)
			)
			(layer "B.SilkS")
		)
		(fp_line
			(start 0.7874 -0.4064)
			(end -0.7874 -0.4064)
			(stroke
				(width 0.1524)
				(type default)
			)
			(layer "B.SilkS")
		)
		(fp_line
			(start -0.7874 0.4064)
			(end 0.7874 0.4064)
			(stroke
				(width 0.1524)
				(type default)
			)
			(layer "B.SilkS")
		)
		(fp_line
			(start -0.7874 -0.4064)
			(end -0.7874 0.4064)
			(stroke
				(width 0.1524)
				(type default)
			)
			(layer "B.SilkS")
		)
		(fp_line
			(start 0.67945 0.3048)
			(end 0.67945 -0.305054)
			(stroke
				(width 0.1)
				(type default)
			)
			(layer "B.Fab")
		)
		(fp_line
			(start 0.67945 -0.305054)
			(end 0.12065 -0.305054)
			(stroke
				(width 0.1)
				(type default)
			)
			(layer "B.Fab")
		)
		(fp_line
			(start 0.12065 0.3048)
			(end 0.67945 0.3048)
			(stroke
				(width 0.1)
				(type default)
			)
			(layer "B.Fab")
		)
		(fp_line
			(start 0.12065 0.2794)
			(end 0.12065 0.3048)
			(stroke
				(width 0.1)
				(type default)
			)
			(layer "B.Fab")
		)
		(fp_line
			(start 0.12065 -0.2794)
			(end -0.12065 -0.2794)
			(stroke
				(width 0.1)
				(type default)
			)
			(layer "B.Fab")
		)
		(fp_line
			(start 0.12065 -0.305054)
			(end 0.12065 -0.2794)
			(stroke
				(width 0.1)
				(type default)
			)
			(layer "B.Fab")
		)
		(fp_line
			(start -0.120396 0.3048)
			(end -0.120396 0.2794)
			(stroke
				(width 0.1)
				(type default)
			)
			(layer "B.Fab")
		)
		(fp_line
			(start -0.120396 0.2794)
			(end 0.12065 0.2794)
			(stroke
				(width 0.1)
				(type default)
			)
			(layer "B.Fab")
		)
		(fp_line
			(start -0.12065 -0.2794)
			(end -0.12065 -0.3048)
			(stroke
				(width 0.1)
				(type default)
			)
			(layer "B.Fab")
		)
		(fp_line
			(start -0.12065 -0.3048)
			(end -0.67945 -0.3048)
			(stroke
				(width 0.1)
				(type default)
			)
			(layer "B.Fab")
		)
		(fp_line
			(start -0.67945 0.3048)
			(end -0.120396 0.3048)
			(stroke
				(width 0.1)
				(type default)
			)
			(layer "B.Fab")
		)
		(fp_line
			(start -0.67945 -0.3048)
			(end -0.67945 0.3048)
			(stroke
				(width 0.1)
				(type default)
			)
			(layer "B.Fab")
		)
		(pad "1" smd circle
			(at 0.40005 0)
			(size 0 0)
			(layers "B.Cu" "B.Mask" "B.Paste")
			(net "PD_CHE_CPU0_DIMM_SAA")
		)
		(pad "2" smd circle
			(at -0.40005 0)
			(size 0 0)
			(layers "B.Cu" "B.Mask" "B.Paste")
			(net "GND")
		)
	)
	(footprint ""
		(layer "B.Cu")
		(at 343.105994 -395.148562 90)
		(property "Reference" "C600"
			(at 0 0 90)
			(layer "B.SilkS")
			(hide yes)
			(effects
				(font
					(size 1.27 1.27)
				)
				(justify mirror)
			)
		)
		(property "Value" ""
			(at 0 0 90)
			(layer "B.Fab")
			(effects
				(font
					(size 1.27 1.27)
				)
				(justify mirror)
			)
		)
		(duplicate_pad_numbers_are_jumpers no)
		(fp_line
			(start 0.299974 -0.150114)
			(end -0.299974 -0.150114)
			(stroke
				(width 0.1)
				(type default)
			)
			(layer "B.Fab")
		)
		(fp_line
			(start -0.299974 -0.150114)
			(end -0.299974 0.150114)
			(stroke
				(width 0.1)
				(type default)
			)
			(layer "B.Fab")
		)
		(fp_line
			(start 0.299974 0.150114)
			(end 0.299974 -0.150114)
			(stroke
				(width 0.1)
				(type default)
			)
			(layer "B.Fab")
		)
		(fp_line
			(start -0.299974 0.150114)
			(end 0.299974 0.150114)
			(stroke
				(width 0.1)
				(type default)
			)
			(layer "B.Fab")
		)
		(pad "1" smd rect
			(at 0.2667 0 270)
			(size 0.3048 0.381)
			(layers "B.Cu" "B.Mask" "B.Paste")
			(net "P1V8_CPU0_RT1_1A")
		)
		(pad "2" smd rect
			(at -0.2667 0 270)
			(size 0.3048 0.381)
			(layers "B.Cu" "B.Mask" "B.Paste")
			(net "GND")
		)
	)
	(footprint ""
		(layer "B.Cu")
		(at 406.666954 -175.3489 90)
		(property "Reference" "PC598"
			(at 6.709664 -0.521462 270)
			(unlocked yes)
			(layer "B.SilkS")
			(effects
				(font
					(size 0.7874 0.5842)
					(thickness 0.1524)
				)
				(justify left mirror)
			)
		)
		(property "Value" ""
			(at 0 0 90)
			(layer "B.Fab")
			(effects
				(font
					(size 1.27 1.27)
				)
				(justify mirror)
			)
		)
		(duplicate_pad_numbers_are_jumpers no)
		(fp_line
			(start 4.533392 -2.249932)
			(end -4.533392 -2.249932)
			(stroke
				(width 0.1524)
				(type default)
			)
			(layer "B.SilkS")
		)
		(fp_line
			(start -4.533392 -2.249932)
			(end -4.533392 2.249932)
			(stroke
				(width 0.1524)
				(type default)
			)
			(layer "B.SilkS")
		)
		(fp_line
			(start 4.533392 2.249932)
			(end 4.533392 -2.249932)
			(stroke
				(width 0.1524)
				(type default)
			)
			(layer "B.SilkS")
		)
		(fp_line
			(start -4.533392 2.249932)
			(end 4.533392 2.249932)
			(stroke
				(width 0.1524)
				(type default)
			)
			(layer "B.SilkS")
		)
		(fp_rect
			(start 4.533392 -2.326132)
			(end 5.39242 2.326132)
			(stroke
				(width 0)
				(type default)
			)
			(fill yes)
			(layer "B.SilkS")
		)
		(fp_line
			(start 3.750056 -2.249932)
			(end -3.750056 -2.249932)
			(stroke
				(width 0.1)
				(type default)
			)
			(layer "B.Fab")
		)
		(fp_line
			(start -3.750056 -2.249932)
			(end -3.750056 2.249932)
			(stroke
				(width 0.1)
				(type default)
			)
			(layer "B.Fab")
		)
		(fp_line
			(start 3.750056 2.249932)
			(end 3.750056 -2.249932)
			(stroke
				(width 0.1)
				(type default)
			)
			(layer "B.Fab")
		)
		(fp_line
			(start -3.750056 2.249932)
			(end 3.750056 2.249932)
			(stroke
				(width 0.1)
				(type default)
			)
			(layer "B.Fab")
		)
		(fp_text user "+"
			(at 6.322314 0.786384 0)
			(unlocked yes)
			(layer "B.SilkS")
			(effects
				(font
					(size 1.905 1.4224)
					(thickness 0.1524)
				)
				(justify left mirror)
			)
		)
		(fp_text user "-"
			(at -4.060698 2.725674 90)
			(unlocked yes)
			(layer "B.SilkS")
			(effects
				(font
					(size 1.905 1.4224)
					(thickness 0.1524)
				)
				(justify left mirror)
			)
		)
		(fp_text user "-"
			(at -4.8514 -0.14605 90)
			(unlocked yes)
			(layer "B.Fab")
			(effects
				(font
					(size 1.905 1.4224)
					(thickness 0.1524)
				)
				(justify left mirror)
			)
		)
		(fp_text user "+"
			(at 6.322314 0.786384 0)
			(unlocked yes)
			(layer "B.Fab")
			(effects
				(font
					(size 1.905 1.4224)
					(thickness 0.1524)
				)
				(justify left mirror)
			)
		)
		(pad "1" smd rect
			(at 3.199892 0 270)
			(size 2.413 2.8194)
			(layers "B.Cu" "B.Mask" "B.Paste")
			(net "PVDDCR_SOC_P0")
		)
		(pad "2" smd rect
			(at -3.199892 0 270)
			(size 2.413 2.8194)
			(layers "B.Cu" "B.Mask" "B.Paste")
			(net "GND")
		)
	)
)
